# SCM (Grand Teton) — schematic netlist excerpt (pin names and nets, part order shuffled) for the footprints in the layout excerpt that follows; sources: Cadence DE-HDL packaged netlist, KiCad conversion of 12092022_DA0F0TMDCD0_F0T_Management_Board_D_brd_V3_OCP.brd

R485  Q_RES  33.2 1% CHIP  pkg 0402LF  page 45 : A = SPI_PCH_MUXED_CS0_N ; B = SPI_PCH_CS0_FLASH_R1_N
C297  Q_CAP  0.1UF 25V 10% X7R  pkg 0402  page 52 : A = P3V3_LDO ; B = GND

(kicad_pcb
	(version 20260206)
	(generator "pcbnew")
	(generator_version "10.0")
	(general
		(thickness 1.6)
		(legacy_teardrops no)
	)
	(paper "A4")
	(title_block
		(title "12092022_DA0F0TMDCD0_F0T_Management_Board_D_brd_V3_OCP.brd")
		(comment 1 "Grand Teton / footprints 577-578 of 1440")
	)
	(layers
		(0 "F.Cu" signal "TOP")
		(4 "In1.Cu" signal "GND")
		(6 "In2.Cu" signal "IN1")
		(8 "In3.Cu" signal "GND1")
		(10 "In4.Cu" signal "IN2")
		(12 "In5.Cu" signal "VCC")
		(14 "In6.Cu" signal "VCC1")
		(16 "In7.Cu" signal "IN3")
		(18 "In8.Cu" signal "GND2")
		(20 "In9.Cu" signal "IN4")
		(22 "In10.Cu" signal "GND3")
		(2 "B.Cu" signal "BOTTOM")
		(9 "F.Adhes" user "F.Adhesive")
		(11 "B.Adhes" user "B.Adhesive")
		(13 "F.Paste" user "Package Geometry/Pastemask Top")
		(15 "B.Paste" user "Package Geometry/Pastemask Bottom")
		(5 "F.SilkS" user "Ref Des/Silkscreen Top")
		(7 "B.SilkS" user "Ref Des/Silkscreen Bottom")
		(1 "F.Mask" user "Board Geometry/Soldermask Top")
		(3 "B.Mask" user "Board Geometry/Soldermask Bottom")
		(17 "Dwgs.User" user "User.Drawings")
		(19 "Cmts.User" user "User.Comments")
		(21 "Eco1.User" user "User.Eco1")
		(23 "Eco2.User" user "User.Eco2")
		(25 "Edge.Cuts" user "Board Geometry/Outline")
		(27 "Margin" user)
		(31 "F.CrtYd" user "Package Geometry/Place Bound Top")
		(29 "B.CrtYd" user "Package Geometry/Place Bound Bottom")
		(35 "F.Fab" user "Ref Des/Assembly Top")
		(33 "B.Fab" user "Ref Des/Assembly Bottom")
	)
	(footprint ""
		(layer "F.Cu")
		(at 40.900604 -87.679784 90)
		(property "Reference" "R485"
			(at 0 0 90)
			(layer "F.SilkS")
			(hide yes)
			(effects
				(font
					(size 1.27 1.27)
				)
			)
		)
		(property "Value" ""
			(at 0 0 90)
			(layer "F.Fab")
			(effects
				(font
					(size 1.27 1.27)
				)
			)
		)
		(duplicate_pad_numbers_are_jumpers no)
		(fp_line
			(start 0.7874 -0.4064)
			(end 0.7874 0.4064)
			(stroke
				(width 0.1524)
				(type default)
			)
			(layer "F.SilkS")
		)
		(fp_line
			(start -0.7874 -0.4064)
			(end 0.7874 -0.4064)
			(stroke
				(width 0.1524)
				(type default)
			)
			(layer "F.SilkS")
		)
		(fp_line
			(start 0.7874 0.4064)
			(end -0.7874 0.4064)
			(stroke
				(width 0.1524)
				(type default)
			)
			(layer "F.SilkS")
		)
		(fp_line
			(start -0.7874 0.4064)
			(end -0.7874 -0.4064)
			(stroke
				(width 0.1524)
				(type default)
			)
			(layer "F.SilkS")
		)
		(fp_line
			(start -0.12065 -0.305054)
			(end -0.12065 -0.2794)
			(stroke
				(width 0.1)
				(type default)
			)
			(layer "F.Fab")
		)
		(fp_line
			(start -0.67945 -0.305054)
			(end -0.12065 -0.305054)
			(stroke
				(width 0.1)
				(type default)
			)
			(layer "F.Fab")
		)
		(fp_line
			(start 0.67945 -0.3048)
			(end 0.67945 0.3048)
			(stroke
				(width 0.1)
				(type default)
			)
			(layer "F.Fab")
		)
		(fp_line
			(start 0.12065 -0.3048)
			(end 0.67945 -0.3048)
			(stroke
				(width 0.1)
				(type default)
			)
			(layer "F.Fab")
		)
		(fp_line
			(start 0.12065 -0.2794)
			(end 0.12065 -0.3048)
			(stroke
				(width 0.1)
				(type default)
			)
			(layer "F.Fab")
		)
		(fp_line
			(start -0.12065 -0.2794)
			(end 0.12065 -0.2794)
			(stroke
				(width 0.1)
				(type default)
			)
			(layer "F.Fab")
		)
		(fp_line
			(start 0.120396 0.2794)
			(end -0.12065 0.2794)
			(stroke
				(width 0.1)
				(type default)
			)
			(layer "F.Fab")
		)
		(fp_line
			(start -0.12065 0.2794)
			(end -0.12065 0.3048)
			(stroke
				(width 0.1)
				(type default)
			)
			(layer "F.Fab")
		)
		(fp_line
			(start 0.67945 0.3048)
			(end 0.120396 0.3048)
			(stroke
				(width 0.1)
				(type default)
			)
			(layer "F.Fab")
		)
		(fp_line
			(start 0.120396 0.3048)
			(end 0.120396 0.2794)
			(stroke
				(width 0.1)
				(type default)
			)
			(layer "F.Fab")
		)
		(fp_line
			(start -0.12065 0.3048)
			(end -0.67945 0.3048)
			(stroke
				(width 0.1)
				(type default)
			)
			(layer "F.Fab")
		)
		(fp_line
			(start -0.67945 0.3048)
			(end -0.67945 -0.305054)
			(stroke
				(width 0.1)
				(type default)
			)
			(layer "F.Fab")
		)
		(pad "1" smd circle
			(at -0.40005 0 90)
			(size 0 0)
			(layers "F.Cu" "F.Mask" "F.Paste")
			(net "SPI_PCH_MUXED_CS0_N")
		)
		(pad "2" smd circle
			(at 0.40005 0 90)
			(size 0 0)
			(layers "F.Cu" "F.Mask" "F.Paste")
			(net "SPI_PCH_CS0_FLASH_R1_N")
		)
	)
	(footprint ""
		(layer "F.Cu")
		(at 11.4554 -61.214 180)
		(property "Reference" "C297"
			(at 0 0 180)
			(layer "F.SilkS")
			(hide yes)
			(effects
				(font
					(size 1.27 1.27)
				)
			)
		)
		(property "Value" ""
			(at 0 0 180)
			(layer "F.Fab")
			(effects
				(font
					(size 1.27 1.27)
				)
			)
		)
		(duplicate_pad_numbers_are_jumpers no)
		(fp_line
			(start 0.7874 0.4064)
			(end -0.7874 0.4064)
			(stroke
				(width 0.1524)
				(type default)
			)
			(layer "F.SilkS")
		)
		(fp_line
			(start 0.7874 -0.4064)
			(end 0.7874 0.4064)
			(stroke
				(width 0.1524)
				(type default)
			)
			(layer "F.SilkS")
		)
		(fp_line
			(start -0.7874 0.4064)
			(end -0.7874 -0.4064)
			(stroke
				(width 0.1524)
				(type default)
			)
			(layer "F.SilkS")
		)
		(fp_line
			(start -0.7874 -0.4064)
			(end 0.7874 -0.4064)
			(stroke
				(width 0.1524)
				(type default)
			)
			(layer "F.SilkS")
		)
		(fp_line
			(start 0.67945 0.3048)
			(end 0.120396 0.3048)
			(stroke
				(width 0.1)
				(type default)
			)
			(layer "F.Fab")
		)
		(fp_line
			(start 0.67945 -0.3048)
			(end 0.67945 0.3048)
			(stroke
				(width 0.1)
				(type default)
			)
			(layer "F.Fab")
		)
		(fp_line
			(start 0.12065 -0.2794)
			(end 0.12065 -0.3048)
			(stroke
				(width 0.1)
				(type default)
			)
			(layer "F.Fab")
		)
		(fp_line
			(start 0.12065 -0.3048)
			(end 0.67945 -0.3048)
			(stroke
				(width 0.1)
				(type default)
			)
			(layer "F.Fab")
		)
		(fp_line
			(start 0.120396 0.3048)
			(end 0.120396 0.2794)
			(stroke
				(width 0.1)
				(type default)
			)
			(layer "F.Fab")
		)
		(fp_line
			(start 0.120396 0.2794)
			(end -0.12065 0.2794)
			(stroke
				(width 0.1)
				(type default)
			)
			(layer "F.Fab")
		)
		(fp_line
			(start -0.12065 0.3048)
			(end -0.67945 0.3048)
			(stroke
				(width 0.1)
				(type default)
			)
			(layer "F.Fab")
		)
		(fp_line
			(start -0.12065 0.2794)
			(end -0.12065 0.3048)
			(stroke
				(width 0.1)
				(type default)
			)
			(layer "F.Fab")
		)
		(fp_line
			(start -0.12065 -0.2794)
			(end 0.12065 -0.2794)
			(stroke
				(width 0.1)
				(type default)
			)
			(layer "F.Fab")
		)
		(fp_line
			(start -0.12065 -0.305054)
			(end -0.12065 -0.2794)
			(stroke
				(width 0.1)
				(type default)
			)
			(layer "F.Fab")
		)
		(fp_line
			(start -0.67945 0.3048)
			(end -0.67945 -0.305054)
			(stroke
				(width 0.1)
				(type default)
			)
			(layer "F.Fab")
		)
		(fp_line
			(start -0.67945 -0.305054)
			(end -0.12065 -0.305054)
			(stroke
				(width 0.1)
				(type default)
			)
			(layer "F.Fab")
		)
		(pad "1" smd circle
			(at -0.40005 0 180)
			(size 0 0)
			(layers "F.Cu" "F.Mask" "F.Paste")
			(net "P3V3_LDO")
		)
		(pad "2" smd circle
			(at 0.40005 0 180)
			(size 0 0)
			(layers "F.Cu" "F.Mask" "F.Paste")
			(net "GND")
		)
	)
)
